PROPERTY_NAME!OWNER!CONCEPT!ALLEGRO!TRANSFER!WINNING_VALUE!TYPE!
XTALK_SENSITIVE_TIME!4!1!1!0!0!0!
VOLTAGE_SOURCE_PIN!4!1!1!0!0!0!
SUBNET_NAME!4!1!1!0!0!0!
SHORTING_SCHEME!4!1!1!0!0!0!
PIN_SIGNAL_MODEL!4!1!1!1!0!0!
PIN_ESCAPE!4!1!1!0!0!0!
PINUSE!4!1!1!0!0!0!
NO_VIA_CONNECT!4!1!1!0!0!0!
NO_SWAP_PIN!4!1!1!0!0!0!
NO_PIN_ESCAPE!4!1!1!0!0!0!
NO_DRC!4!1!1!0!0!0!
NET_SHORT!4!1!1!0!0!0!
MIN_SETUP!4!1!1!0!0!0!
MIN_HOLD!4!1!1!0!0!0!
IDF_OWNER!4!1!1!0!0!0!
FIXED!4!1!1!0!0!0!
CLIP_DRAWING!4!1!1!0!0!0!
GROUP!2!1!1!0!0!0!
SWAP_GROUP!2!1!1!0!0!0!
SLOTNAME!2!1!1!0!0!0!
REF_DES_FOR_ASSIGN!2!1!1!0!0!0!
NO_SWAP_PIN!2!1!1!0!0!0!
NO_SWAP_GATE_EXT!2!1!1!0!0!0!
NO_SWAP_GATE!2!1!1!0!0!0!
HARD_LOCATION!2!1!1!0!0!0!
NO_XNET_CONNECTION!1!1!1!1!0!0!
MWO_NAME!1!1!1!1!0!0!
RFGROUP!1!1!1!1!0!0!
RFDCNET!1!1!1!1!0!0!
RFBLOCK!1!1!1!1!0!0!
RFPADTYPE!1!1!1!1!0!0!
RFDRANAME!1!1!1!1!0!0!
RFPADANGLE!1!1!1!1!0!0!
RFHOLEDIAMETER!1!1!1!1!0!0!
RFPADLENGTH2!1!1!1!1!0!0!
RFPADLENGTH1!1!1!1!1!0!0!
RFPADDIAMETER2!1!1!1!1!0!0!
RFPADDIAMETER1!1!1!1!1!0!0!
RFPADDIAMETER!1!1!1!1!0!0!
RFPADLINEWIDTH2!1!1!1!1!0!0!
RFPADLINEWIDTH1!1!1!1!1!0!0!
RFPADENDLAYER!1!1!1!1!0!0!
RFPADBEGINLAYER!1!1!1!1!0!0!
RFPADSSMNAME2!1!1!1!1!0!0!
RFPADSSMNAME1!1!1!1!1!0!0!
RFPADSTACKNAME!1!1!1!1!0!0!
RFINDUCTANCE!1!1!1!1!0!0!
RFRESISTANCE!1!1!1!1!0!0!
RFCAPACITANCE!1!1!1!1!0!0!
RFNUMBERTURNS!1!1!1!1!0!0!
RFNUMBERPAIRS!1!1!1!1!0!0!
RFNUMBERLEGS!1!1!1!1!0!0!
RFBENDMODE!1!1!1!1!0!0!
RFMITERFRACTION!1!1!1!1!0!0!
RFFREQUENCY!1!1!1!1!0!0!
RFDEPTH!1!1!1!1!0!0!
RFRADIUS!1!1!1!1!0!0!
RFOFFSETY!1!1!1!1!0!0!
RFOFFSETX!1!1!1!1!0!0!
RFSPACING15!1!1!1!1!0!0!
RFSPACING14!1!1!1!1!0!0!
RFSPACING13!1!1!1!1!0!0!
RFSPACING12!1!1!1!1!0!0!
RFSPACING11!1!1!1!1!0!0!
RFSPACING10!1!1!1!1!0!0!
RFSPACING9!1!1!1!1!0!0!
RFSPACING8!1!1!1!1!0!0!
RFSPACING7!1!1!1!1!0!0!
RFSPACING6!1!1!1!1!0!0!
RFSPACING5!1!1!1!1!0!0!
RFSPACING4!1!1!1!1!0!0!
RFSPACING3!1!1!1!1!0!0!
RFSPACING2!1!1!1!1!0!0!
RFSPACING1!1!1!1!1!0!0!
RFSPACING!1!1!1!1!0!0!
RFLENGTH8!1!1!1!1!0!0!
RFLENGTH7!1!1!1!1!0!0!
RFLENGTH6!1!1!1!1!0!0!
RFLENGTH5!1!1!1!1!0!0!
RFLENGTH4!1!1!1!1!0!0!
RFLENGTH3!1!1!1!1!0!0!
RFLENGTH2!1!1!1!1!0!0!
RFLENGTH1!1!1!1!1!0!0!
RFLENGTH!1!1!1!1!0!0!
RFWIDTH16!1!1!1!1!0!0!
RFWIDTH15!1!1!1!1!0!0!
RFWIDTH14!1!1!1!1!0!0!
RFWIDTH13!1!1!1!1!0!0!
RFWIDTH12!1!1!1!1!0!0!
RFWIDTH11!1!1!1!1!0!0!
RFWIDTH10!1!1!1!1!0!0!
RFWIDTH9!1!1!1!1!0!0!
RFWIDTH8!1!1!1!1!0!0!
RFWIDTH7!1!1!1!1!0!0!
RFWIDTH6!1!1!1!1!0!0!
RFWIDTH5!1!1!1!1!0!0!
RFWIDTH4!1!1!1!1!0!0!
RFWIDTH3!1!1!1!1!0!0!
RFWIDTH2!1!1!1!1!0!0!
RFWIDTH1!1!1!1!1!0!0!
RFWIDTH!1!1!1!1!0!0!
RFANGLE1!1!1!1!1!0!0!
RFANGLE!1!1!1!1!0!0!
RFFLIPMODE!1!1!1!1!0!0!
RFCOUPLINGMODE!1!1!1!1!0!0!
RFLAYER16!1!1!1!1!0!0!
RFLAYER15!1!1!1!1!0!0!
RFLAYER14!1!1!1!1!0!0!
RFLAYER13!1!1!1!1!0!0!
RFLAYER12!1!1!1!1!0!0!
RFLAYER11!1!1!1!1!0!0!
RFLAYER10!1!1!1!1!0!0!
RFLAYER9!1!1!1!1!0!0!
RFLAYER8!1!1!1!1!0!0!
RFLAYER7!1!1!1!1!0!0!
RFLAYER6!1!1!1!1!0!0!
RFLAYER5!1!1!1!1!0!0!
RFLAYER4!1!1!1!1!0!0!
RFLAYER3!1!1!1!1!0!0!
RFLAYER2!1!1!1!1!0!0!
RFLAYER1!1!1!1!1!0!0!
RFLAYER!1!1!1!1!0!0!
RFELEMENTTYPE!1!1!1!1!0!0!
ISRFELEMENT!1!1!1!1!0!0!
VOLT_TEMP_MODEL!1!1!1!0!0!0!
VOLTAGE!1!1!1!0!0!0!
VALUE!1!1!1!0!0!0!
T_TEMPERATURE!1!1!1!0!0!0!
TOL!1!1!1!0!0!0!
TH_TECHNOLOGY!1!1!1!0!0!0!
TH_QUALITY!1!1!1!0!0!0!
TH_PACK_PARM!1!1!1!0!0!0!
TH_LOCATION!1!1!1!0!0!0!
TH_JC_RES!1!1!1!0!0!0!
TH_HEATSINK!1!1!1!0!0!0!
TH_GLUERES!1!1!1!0!0!0!
TH_FUNC_PARM!1!1!1!0!0!0!
TH_DEV_TYPE!1!1!1!0!0!0!
TH_DEV_CLASS!1!1!1!0!0!0!
TH_COMPLEXITY!1!1!1!0!0!0!
TH_CLEARANCE_MATERIAL!1!1!1!0!0!0!
TH_CLEARANCE_AREA!1!1!1!0!0!0!
TH_CLEARANCE!1!1!1!0!0!0!
TH_CB_RES!1!1!1!0!0!0!
TH_APPLICATION!1!1!1!0!0!0!
TERMINATOR_PACK!1!1!1!0!0!0!
ASI_MODEL!1!1!1!1!0!0!
SIGNAL_MODEL!1!1!1!1!0!0!
ROOM!1!1!1!0!0!0!
RATED_VOLTAGE!1!1!1!0!0!0!
RATED_POWER!1!1!1!0!0!0!
RATED_MAX_TEMP!1!1!1!0!0!0!
RATED_CURRENT!1!1!1!0!0!0!
PLACE_TAG!1!1!1!0!0!0!
PIN_ESCAPE!1!1!1!0!0!0!
NO_SWAP_PIN!1!1!1!0!0!0!
NO_SWAP_GATE_EXT!1!1!1!0!0!0!
NO_SWAP_GATE!1!1!1!0!0!0!
NO_SWAP_COMP!1!1!1!0!0!0!
NO_ROUTE!1!1!1!0!0!0!
NO_PIN_ESCAPE!1!1!1!0!0!0!
MAX_POWER_DISS!1!1!1!0!0!0!
J_TEMPERATURE!1!1!1!0!0!0!
INSERTION_CODE!1!1!1!0!0!0!
HEIGHT!1!1!1!0!0!0!
HARD_LOCATION!1!1!1!0!0!0!
FIXED!1!1!1!0!0!0!
FIX_ALL!1!1!1!0!0!0!
FAILURE_RATE!1!1!1!0!0!0!
EMC_CRITICAL_IC!1!1!1!0!0!0!
EMC_COMP_TYPE!1!1!1!0!0!0!
DEVICE_LABEL!1!1!1!0!0!0!
DEPTH_STOP!1!1!1!0!0!0!
DENSE_COMPONENT!1!1!1!0!0!0!
C_TEMPERATURE!1!1!1!0!0!0!
CURRENT!1!1!1!0!0!0!
COMPONENT_WEIGHT!1!1!1!0!0!0!
BOM_IGNORE!1!1!1!0!0!0!
AUTO_RENAME!1!1!1!0!0!0!
AUTO_GENERATED_TERM!1!1!1!0!0!0!
ALT_SYMBOLS!1!1!1!0!0!0!
RFSPLIT!3!1!1!1!0!0!
XTALK_SENSITIVE_TIME!3!1!1!0!0!0!
XTALK_IGNORE_NETS!3!1!1!0!0!0!
XTALK_ACTIVE_TIME!3!1!1!0!0!0!
WEIGHT!3!1!1!0!0!0!
VOLTAGE_LAYER!3!1!1!0!0!0!
VOLTAGE!3!1!1!0!0!0!
VIA_LIST!3!1!1!0!0!0!
TS_ALLOWED!3!1!1!0!0!0!
TOPOLOGY_TEMPLATE_REVISION!3!1!1!0!0!0!
TOPOLOGY_TEMPLATE!3!1!1!0!0!0!
TIMING_DELAY_OVERRIDE!3!1!1!0!0!0!
TESTER_GUARDBAND!3!1!1!0!0!0!
SUBNET_NAME!3!1!1!0!0!0!
STUB_LENGTH!3!1!1!0!0!0!
SHIELD_TYPE!3!1!1!0!0!0!
SHIELD_NET!3!1!1!0!0!0!
SHORTING_SCHEME!3!1!1!0!0!0!
SAME_NET!3!1!1!0!0!0!
ROUTE_TO_SHAPE!3!1!1!0!0!0!
ROUTE_PRIORITY!3!1!1!0!0!0!
RELATIVE_PROPAGATION_DELAY!3!1!1!0!0!0!
RATSNEST_SCHEDULE!3!1!1!0!0!0!
PULSE_PARAM!3!1!1!0!0!0!
PROPAGATION_DELAY!3!1!1!0!0!0!
PROBE_NUMBER!3!1!1!0!0!0!
NO_TEST!3!1!1!0!0!0!
NO_ROUTE!3!1!1!0!0!0!
NO_RIPUP!3!1!1!0!0!0!
NO_RAT!3!1!1!0!0!0!
NO_PIN_ESCAPE!3!1!1!0!0!0!
NO_GLOSS!3!1!1!0!0!0!
NET_SPACING_TYPE!3!1!1!0!0!0!
NET_SCHEDULE!3!1!1!0!0!0!
NET_PHYSICAL_TYPE!3!1!1!0!0!0!
MIN_NOISE_MARGIN!3!1!1!0!0!0!
MIN_NECK_WIDTH!3!1!1!0!0!0!
MIN_LINE_WIDTH!3!1!1!0!0!0!
MIN_FIRST_SWITCH!3!1!1!0!0!0!
MIN_BVIA_STAGGER!3!1!1!0!0!0!
MIN_BVIA_GAP!3!1!1!0!0!0!
MIN_BOND_LENGTH!3!1!1!0!0!0!
MAX_XTALK!3!1!1!0!0!0!
MAX_VIA_COUNT!3!1!1!0!0!0!
MAX_SSN!3!1!1!0!0!0!
MAX_PEAK_XTALK!3!1!1!0!0!0!
MAX_PARALLEL!3!1!1!0!0!0!
MAX_OVERSHOOT!3!1!1!0!0!0!
MAX_FINAL_SETTLE!3!1!1!0!0!0!
MAX_EXPOSED_LENGTH!3!1!1!0!0!0!
MAX_BVIA_STAGGER!3!1!1!0!0!0!
MAX_BOND_LENGTH!3!1!1!0!0!0!
MATCHED_DELAY!3!1!1!0!0!0!
LOAD_TERM_VAL!3!1!1!0!0!0!
IMPEDANCE_RULE!3!1!1!0!0!0!
FIXED!3!1!1!0!0!0!
FIRST_INCIDENT!3!1!1!0!0!0!
EMC_CRITICAL_NET!3!1!1!0!0!0!
ELECTRICAL_CONSTRAINT_SET!3!1!1!0!0!0!
EDGE_SENS!3!1!1!0!0!0!
ECL!3!1!1!0!0!0!
DRIVER_TERM_VAL!3!1!1!0!0!0!
DIFFP_LENGTH_TOL!3!1!1!0!0!0!
DIFFP_2ND_LENGTH!3!1!1!0!0!0!
DIFFERENTIAL_PAIR!3!1!1!0!0!0!
DELAY_RULE!3!1!1!0!0!0!
CLOCK_NET!3!1!1!0!0!0!
CLK_SKEW_MIN!3!1!1!0!0!0!
CLK_SKEW_MAX!3!1!1!0!0!0!
CLK_2OUT_MIN!3!1!1!0!0!0!
CLK_2OUT_MAX!3!1!1!0!0!0!
BUS_NAME!3!1!1!0!0!0!
ASSIGN_TOPOLOGY!3!1!1!0!0!0!
